G04 #@! TF.GenerationSoftware,KiCad,Pcbnew,(5.0.1)-3*
G04 #@! TF.CreationDate,2019-04-10T15:36:06+02:00*
G04 #@! TF.ProjectId,discovery,646973636F766572792E6B696361645F,rev?*
G04 #@! TF.SameCoordinates,PX4c4640PY8a48028*
G04 #@! TF.FileFunction,Paste,Top*
G04 #@! TF.FilePolarity,Positive*
%FSLAX46Y46*%
G04 Gerber Fmt 4.6, Leading zero omitted, Abs format (unit mm)*
%MOMM*%
%LPD*%
G01*
G04 APERTURE LIST*
G04 APERTURE END LIST*
M02*
